(kicad_pcb
	(version 20260206)
	(generator "pcbnew")
	(generator_version "10.0")
	(general
		(thickness 1.6)
		(legacy_teardrops no)
	)
	(paper "A4")
	(title_block
		(title "15969-1a.1015WZS0858.brd")
		(comment 1 "Tioga Pass / footprints 290-295 of 295")
	)
	(layers
		(0 "F.Cu" signal "TOP")
		(4 "In1.Cu" signal "L2GND")
		(6 "In2.Cu" signal "L3")
		(8 "In3.Cu" signal "L4")
		(10 "In4.Cu" signal "L5GND")
		(2 "B.Cu" signal "BOTTOM")
		(9 "F.Adhes" user "F.Adhesive")
		(11 "B.Adhes" user "B.Adhesive")
		(13 "F.Paste" user "Package Geometry/Pastemask Top")
		(15 "B.Paste" user "Package Geometry/Pastemask Bottom")
		(5 "F.SilkS" user "Ref Des/Silkscreen Top")
		(7 "B.SilkS" user "Ref Des/Silkscreen Bottom")
		(1 "F.Mask" user "Board Geometry/Soldermask Top")
		(3 "B.Mask" user "Board Geometry/Soldermask Bottom")
		(17 "Dwgs.User" user "User.Drawings")
		(19 "Cmts.User" user "User.Comments")
		(21 "Eco1.User" user "User.Eco1")
		(23 "Eco2.User" user "User.Eco2")
		(25 "Edge.Cuts" user "Board Geometry/Outline")
		(27 "Margin" user)
		(31 "F.CrtYd" user "Package Geometry/Place Bound Top")
		(29 "B.CrtYd" user "Package Geometry/Place Bound Bottom")
		(35 "F.Fab" user "Ref Des/Assembly Top")
		(33 "B.Fab" user "Ref Des/Assembly Bottom")
	)
	(footprint ""
		(layer "B.Cu")
		(at 122.809 -4.6863 -90)
		(property "Reference" "R19"
			(at 0 0 90)
			(layer "B.SilkS")
			(hide yes)
			(effects
				(font
					(size 1.27 1.27)
				)
				(justify mirror)
			)
		)
		(property "Value" "4K7R2F-GP"
			(at -0.064008 -3.993896 270)
			(unlocked yes)
			(layer "B.Fab")
			(hide yes)
			(effects
				(font
					(size 1.016 1.016)
					(thickness 0.1524)
				)
				(justify mirror)
			)
		)
		(property "Device Type" "R402H16"
			(at -0.064008 -5.517896 270)
			(unlocked yes)
			(layer "B.Fab")
			(hide yes)
			(effects
				(font
					(size 1.016 1.016)
					(thickness 0.1524)
				)
				(justify mirror)
			)
		)
		(duplicate_pad_numbers_are_jumpers no)
		(fp_line
			(start -0.508 -0.9398)
			(end 0.508 -0.9398)
			(stroke
				(width 0.1524)
				(type default)
			)
			(layer "B.SilkS")
		)
		(fp_line
			(start 0.508 -0.9398)
			(end 0.508 0.9398)
			(stroke
				(width 0.1524)
				(type default)
			)
			(layer "B.SilkS")
		)
		(fp_rect
			(start 0.508 0.9398)
			(end -0.508 -0.9398)
			(stroke
				(width 0)
				(type default)
			)
			(fill no)
			(layer "B.CrtYd")
		)
		(fp_rect
			(start 0.508 0.9398)
			(end -0.508 -0.9398)
			(stroke
				(width 0)
				(type default)
			)
			(fill no)
			(layer "B.Fab")
		)
		(pad "1" smd custom
			(at 0 -0.4445 90)
			(size 0.1397 0.1397)
			(layers "B.Cu" "B.Mask" "B.Paste")
			(net "P3V3_STBY")
			(options
				(clearance outline)
				(anchor circle)
			)
			(primitives
				(gr_poly
					(pts
						(arc
							(start -0.1778 0.2794)
							(mid -0.249642 0.249642)
							(end -0.2794 0.1778)
						)
						(arc
							(start -0.2794 -0.1778)
							(mid -0.249642 -0.249642)
							(end -0.1778 -0.2794)
						)
						(arc
							(start 0.1778 -0.2794)
							(mid 0.249642 -0.249642)
							(end 0.2794 -0.1778)
						)
						(arc
							(start 0.2794 0.1778)
							(mid 0.249642 0.249642)
							(end 0.1778 0.2794)
						)
					)
					(width 0)
					(fill yes)
				)
			)
		)
		(pad "2" smd custom
			(at 0 0.4445 90)
			(size 0.1397 0.1397)
			(layers "B.Cu" "B.Mask" "B.Paste")
			(net "SMCLK_PCH_SLOT2")
			(options
				(clearance outline)
				(anchor circle)
			)
			(primitives
				(gr_poly
					(pts
						(arc
							(start -0.1778 0.2794)
							(mid -0.249642 0.249642)
							(end -0.2794 0.1778)
						)
						(arc
							(start -0.2794 -0.1778)
							(mid -0.249642 -0.249642)
							(end -0.1778 -0.2794)
						)
						(arc
							(start 0.1778 -0.2794)
							(mid 0.249642 -0.249642)
							(end 0.2794 -0.1778)
						)
						(arc
							(start 0.2794 0.1778)
							(mid 0.249642 0.249642)
							(end 0.1778 0.2794)
						)
					)
					(width 0)
					(fill yes)
				)
			)
		)
	)
	(footprint ""
		(layer "B.Cu")
		(at 26.3652 -23.6474)
		(property "Reference" "R151"
			(at 0 0 0)
			(layer "B.SilkS")
			(hide yes)
			(effects
				(font
					(size 1.27 1.27)
				)
				(justify mirror)
			)
		)
		(property "Value" "10KR2F-2-GP"
			(at -0.064008 -3.993896 0)
			(unlocked yes)
			(layer "B.Fab")
			(hide yes)
			(effects
				(font
					(size 1.016 1.016)
					(thickness 0.1524)
				)
				(justify mirror)
			)
		)
		(property "Device Type" "R402H16"
			(at -0.064008 -5.517896 0)
			(unlocked yes)
			(layer "B.Fab")
			(hide yes)
			(effects
				(font
					(size 1.016 1.016)
					(thickness 0.1524)
				)
				(justify mirror)
			)
		)
		(duplicate_pad_numbers_are_jumpers no)
		(fp_line
			(start -0.508 -0.9398)
			(end 0.508 -0.9398)
			(stroke
				(width 0.1524)
				(type default)
			)
			(layer "B.SilkS")
		)
		(fp_line
			(start 0.508 -0.9398)
			(end 0.508 0.9398)
			(stroke
				(width 0.1524)
				(type default)
			)
			(layer "B.SilkS")
		)
		(fp_rect
			(start 0.508 0.9398)
			(end -0.508 -0.9398)
			(stroke
				(width 0)
				(type default)
			)
			(fill no)
			(layer "B.CrtYd")
		)
		(fp_rect
			(start 0.508 0.9398)
			(end -0.508 -0.9398)
			(stroke
				(width 0)
				(type default)
			)
			(fill no)
			(layer "B.Fab")
		)
		(pad "1" smd custom
			(at 0 -0.4445 180)
			(size 0.1397 0.1397)
			(layers "B.Cu" "B.Mask" "B.Paste")
			(net "P3V3_STBY")
			(options
				(clearance outline)
				(anchor circle)
			)
			(primitives
				(gr_poly
					(pts
						(arc
							(start -0.1778 0.2794)
							(mid -0.249642 0.249642)
							(end -0.2794 0.1778)
						)
						(arc
							(start -0.2794 -0.1778)
							(mid -0.249642 -0.249642)
							(end -0.1778 -0.2794)
						)
						(arc
							(start 0.1778 -0.2794)
							(mid 0.249642 -0.249642)
							(end 0.2794 -0.1778)
						)
						(arc
							(start 0.2794 0.1778)
							(mid 0.249642 0.249642)
							(end 0.1778 0.2794)
						)
					)
					(width 0)
					(fill yes)
				)
			)
		)
		(pad "2" smd custom
			(at 0 0.4445 180)
			(size 0.1397 0.1397)
			(layers "B.Cu" "B.Mask" "B.Paste")
			(net "ATX_VMONITOR_A0")
			(options
				(clearance outline)
				(anchor circle)
			)
			(primitives
				(gr_poly
					(pts
						(arc
							(start -0.1778 0.2794)
							(mid -0.249642 0.249642)
							(end -0.2794 0.1778)
						)
						(arc
							(start -0.2794 -0.1778)
							(mid -0.249642 -0.249642)
							(end -0.1778 -0.2794)
						)
						(arc
							(start 0.1778 -0.2794)
							(mid 0.249642 -0.249642)
							(end 0.2794 -0.1778)
						)
						(arc
							(start 0.2794 0.1778)
							(mid 0.249642 0.249642)
							(end 0.1778 0.2794)
						)
					)
					(width 0)
					(fill yes)
				)
			)
		)
	)
	(footprint ""
		(layer "B.Cu")
		(at 124.587 -11.7094)
		(property "Reference" "R31"
			(at 0 0 0)
			(layer "B.SilkS")
			(hide yes)
			(effects
				(font
					(size 1.27 1.27)
				)
				(justify mirror)
			)
		)
		(property "Value" "10KR2F-2-GP"
			(at -0.064008 -3.993896 0)
			(unlocked yes)
			(layer "B.Fab")
			(hide yes)
			(effects
				(font
					(size 1.016 1.016)
					(thickness 0.1524)
				)
				(justify mirror)
			)
		)
		(property "Device Type" "R402H16"
			(at -0.064008 -5.517896 0)
			(unlocked yes)
			(layer "B.Fab")
			(hide yes)
			(effects
				(font
					(size 1.016 1.016)
					(thickness 0.1524)
				)
				(justify mirror)
			)
		)
		(duplicate_pad_numbers_are_jumpers no)
		(fp_line
			(start -0.508 -0.9398)
			(end 0.508 -0.9398)
			(stroke
				(width 0.1524)
				(type default)
			)
			(layer "B.SilkS")
		)
		(fp_line
			(start 0.508 -0.9398)
			(end 0.508 0.9398)
			(stroke
				(width 0.1524)
				(type default)
			)
			(layer "B.SilkS")
		)
		(fp_rect
			(start 0.508 0.9398)
			(end -0.508 -0.9398)
			(stroke
				(width 0)
				(type default)
			)
			(fill no)
			(layer "B.CrtYd")
		)
		(fp_rect
			(start 0.508 0.9398)
			(end -0.508 -0.9398)
			(stroke
				(width 0)
				(type default)
			)
			(fill no)
			(layer "B.Fab")
		)
		(pad "1" smd custom
			(at 0 -0.4445 180)
			(size 0.1397 0.1397)
			(layers "B.Cu" "B.Mask" "B.Paste")
			(net "P3V3_STBY")
			(options
				(clearance outline)
				(anchor circle)
			)
			(primitives
				(gr_poly
					(pts
						(arc
							(start -0.1778 0.2794)
							(mid -0.249642 0.249642)
							(end -0.2794 0.1778)
						)
						(arc
							(start -0.2794 -0.1778)
							(mid -0.249642 -0.249642)
							(end -0.1778 -0.2794)
						)
						(arc
							(start 0.1778 -0.2794)
							(mid 0.249642 -0.249642)
							(end 0.2794 -0.1778)
						)
						(arc
							(start 0.2794 0.1778)
							(mid 0.249642 0.249642)
							(end 0.1778 0.2794)
						)
					)
					(width 0)
					(fill yes)
				)
			)
		)
		(pad "2" smd custom
			(at 0 0.4445 180)
			(size 0.1397 0.1397)
			(layers "B.Cu" "B.Mask" "B.Paste")
			(net "SMB_P_HUB_A0")
			(options
				(clearance outline)
				(anchor circle)
			)
			(primitives
				(gr_poly
					(pts
						(arc
							(start -0.1778 0.2794)
							(mid -0.249642 0.249642)
							(end -0.2794 0.1778)
						)
						(arc
							(start -0.2794 -0.1778)
							(mid -0.249642 -0.249642)
							(end -0.1778 -0.2794)
						)
						(arc
							(start 0.1778 -0.2794)
							(mid 0.249642 -0.249642)
							(end 0.2794 -0.1778)
						)
						(arc
							(start 0.2794 0.1778)
							(mid 0.249642 0.249642)
							(end 0.1778 0.2794)
						)
					)
					(width 0)
					(fill yes)
				)
			)
		)
	)
	(footprint ""
		(layer "B.Cu")
		(at 15.8623 -26.5811 -45)
		(property "Reference" "R102"
			(at 0 0 135)
			(layer "B.SilkS")
			(hide yes)
			(effects
				(font
					(size 1.27 1.27)
				)
				(justify mirror)
			)
		)
		(property "Value" "10R2F-L-GP"
			(at -0.063939 -3.993984 315)
			(unlocked yes)
			(layer "B.Fab")
			(hide yes)
			(effects
				(font
					(size 1.016 1.016)
					(thickness 0.1524)
				)
				(justify mirror)
			)
		)
		(property "Device Type" "R402H14"
			(at -0.064299 -5.517754 315)
			(unlocked yes)
			(layer "B.Fab")
			(hide yes)
			(effects
				(font
					(size 1.016 1.016)
					(thickness 0.1524)
				)
				(justify mirror)
			)
		)
		(duplicate_pad_numbers_are_jumpers no)
		(fp_line
			(start -0.508103 -0.939874)
			(end 0.508103 -0.939874)
			(stroke
				(width 0.1524)
				(type default)
			)
			(layer "B.SilkS")
		)
		(fp_line
			(start 0.508103 -0.939874)
			(end 0.508103 0.939874)
			(stroke
				(width 0.1524)
				(type default)
			)
			(layer "B.SilkS")
		)
		(fp_poly
			(pts
				(xy -0.507896 0.939874) (xy -0.507897 -0.939726) (xy 0.508103 -0.939727) (xy 0.508103 0.939874)
			)
			(stroke
				(width 0)
				(type default)
			)
			(fill no)
			(layer "B.CrtYd")
		)
		(fp_poly
			(pts
				(xy -0.507896 0.939874) (xy -0.507897 -0.939726) (xy 0.508103 -0.939727) (xy 0.508103 0.939874)
			)
			(stroke
				(width 0)
				(type default)
			)
			(fill no)
			(layer "B.Fab")
		)
		(pad "1" smd custom
			(at 0 -0.4445 135)
			(size 0.1397 0.1397)
			(layers "B.Cu" "B.Mask" "B.Paste")
			(net "P12V")
			(options
				(clearance outline)
				(anchor circle)
			)
			(primitives
				(gr_poly
					(pts
						(arc
							(start -0.1778 0.2794)
							(mid -0.249642 0.249642)
							(end -0.2794 0.1778)
						)
						(arc
							(start -0.2794 -0.1778)
							(mid -0.249642 -0.249642)
							(end -0.1778 -0.2794)
						)
						(arc
							(start 0.1778 -0.2794)
							(mid 0.249642 -0.249642)
							(end 0.2794 -0.1778)
						)
						(arc
							(start 0.2794 0.1778)
							(mid 0.249642 0.249642)
							(end 0.1778 0.2794)
						)
					)
					(width 0)
					(fill yes)
				)
			)
		)
		(pad "2" smd custom
			(at 0 0.4445 135)
			(size 0.1397 0.1397)
			(layers "B.Cu" "B.Mask" "B.Paste")
			(net "ATX_P12V_SENSE_VP_R")
			(options
				(clearance outline)
				(anchor circle)
			)
			(primitives
				(gr_poly
					(pts
						(arc
							(start -0.1778 0.2794)
							(mid -0.249642 0.249642)
							(end -0.2794 0.1778)
						)
						(arc
							(start -0.2794 -0.1778)
							(mid -0.249642 -0.249642)
							(end -0.1778 -0.2794)
						)
						(arc
							(start 0.1778 -0.2794)
							(mid 0.249642 -0.249642)
							(end 0.2794 -0.1778)
						)
						(arc
							(start 0.2794 0.1778)
							(mid 0.249642 0.249642)
							(end 0.1778 0.2794)
						)
					)
					(width 0)
					(fill yes)
				)
			)
		)
	)
	(footprint ""
		(layer "B.Cu")
		(at 122.9106 -18.5674 90)
		(property "Reference" "CU61"
			(at 0 0 90)
			(layer "B.SilkS")
			(hide yes)
			(effects
				(font
					(size 1.27 1.27)
				)
				(justify mirror)
			)
		)
		(property "Value" "SCD1U16V2KX-3GP"
			(at -1.1811 -2.7051 90)
			(unlocked yes)
			(layer "B.Fab")
			(hide yes)
			(effects
				(font
					(size 1.016 1.016)
					(thickness 0.1524)
				)
				(justify mirror)
			)
		)
		(property "Device Type" "C402H22"
			(at -1.1811 -4.2291 90)
			(unlocked yes)
			(layer "B.Fab")
			(hide yes)
			(effects
				(font
					(size 1.016 1.016)
					(thickness 0.1524)
				)
				(justify mirror)
			)
		)
		(duplicate_pad_numbers_are_jumpers no)
		(fp_rect
			(start 0.4318 0.9525)
			(end -0.4318 -0.9525)
			(stroke
				(width 0)
				(type default)
			)
			(fill no)
			(layer "B.CrtYd")
		)
		(fp_rect
			(start 0.4318 0.9525)
			(end -0.4318 -0.9525)
			(stroke
				(width 0)
				(type default)
			)
			(fill no)
			(layer "B.Fab")
		)
		(pad "1" smd custom
			(at 0 -0.4445 270)
			(size 0.1524 0.1524)
			(layers "B.Cu" "B.Mask" "B.Paste")
			(net "P3V3_USB_HUB")
			(options
				(clearance outline)
				(anchor circle)
			)
			(primitives
				(gr_poly
					(pts
						(arc
							(start 0.3048 0.2032)
							(mid 0.275042 0.275042)
							(end 0.2032 0.3048)
						)
						(arc
							(start -0.2032 0.3048)
							(mid -0.275042 0.275042)
							(end -0.3048 0.2032)
						)
						(arc
							(start -0.3048 -0.2032)
							(mid -0.275042 -0.275042)
							(end -0.2032 -0.3048)
						)
						(arc
							(start 0.2032 -0.3048)
							(mid 0.275042 -0.275042)
							(end 0.3048 -0.2032)
						)
					)
					(width 0)
					(fill yes)
				)
			)
		)
		(pad "2" smd custom
			(at 0 0.4445 270)
			(size 0.1524 0.1524)
			(layers "B.Cu" "B.Mask" "B.Paste")
			(net "GND")
			(options
				(clearance outline)
				(anchor circle)
			)
			(primitives
				(gr_poly
					(pts
						(arc
							(start 0.3048 0.2032)
							(mid 0.275042 0.275042)
							(end 0.2032 0.3048)
						)
						(arc
							(start -0.2032 0.3048)
							(mid -0.275042 0.275042)
							(end -0.3048 0.2032)
						)
						(arc
							(start -0.3048 -0.2032)
							(mid -0.275042 -0.275042)
							(end -0.2032 -0.3048)
						)
						(arc
							(start 0.2032 -0.3048)
							(mid 0.275042 -0.275042)
							(end 0.3048 -0.2032)
						)
					)
					(width 0)
					(fill yes)
				)
			)
		)
	)
	(footprint ""
		(layer "B.Cu")
		(at 41.7195 1.9939 -90)
		(property "Reference" "R50"
			(at 0 0 90)
			(layer "B.SilkS")
			(hide yes)
			(effects
				(font
					(size 1.27 1.27)
				)
				(justify mirror)
			)
		)
		(property "Value" "0R2F-1-GP"
			(at -0.064008 -3.993896 270)
			(unlocked yes)
			(layer "B.Fab")
			(hide yes)
			(effects
				(font
					(size 1.016 1.016)
					(thickness 0.1524)
				)
				(justify mirror)
			)
		)
		(property "Device Type" "R402H16"
			(at -0.064008 -5.517896 270)
			(unlocked yes)
			(layer "B.Fab")
			(hide yes)
			(effects
				(font
					(size 1.016 1.016)
					(thickness 0.1524)
				)
				(justify mirror)
			)
		)
		(duplicate_pad_numbers_are_jumpers no)
		(fp_line
			(start -0.508 -0.9398)
			(end 0.508 -0.9398)
			(stroke
				(width 0.1524)
				(type default)
			)
			(layer "B.SilkS")
		)
		(fp_line
			(start 0.508 -0.9398)
			(end 0.508 0.9398)
			(stroke
				(width 0.1524)
				(type default)
			)
			(layer "B.SilkS")
		)
		(fp_rect
			(start 0.508 0.9398)
			(end -0.508 -0.9398)
			(stroke
				(width 0)
				(type default)
			)
			(fill no)
			(layer "B.CrtYd")
		)
		(fp_rect
			(start 0.508 0.9398)
			(end -0.508 -0.9398)
			(stroke
				(width 0)
				(type default)
			)
			(fill no)
			(layer "B.Fab")
		)
		(pad "1" smd custom
			(at 0 -0.4445 90)
			(size 0.1397 0.1397)
			(layers "B.Cu" "B.Mask" "B.Paste")
			(net "SMCLK_PCH_R")
			(options
				(clearance outline)
				(anchor circle)
			)
			(primitives
				(gr_poly
					(pts
						(arc
							(start -0.1778 0.2794)
							(mid -0.249642 0.249642)
							(end -0.2794 0.1778)
						)
						(arc
							(start -0.2794 -0.1778)
							(mid -0.249642 -0.249642)
							(end -0.1778 -0.2794)
						)
						(arc
							(start 0.1778 -0.2794)
							(mid 0.249642 -0.249642)
							(end 0.2794 -0.1778)
						)
						(arc
							(start 0.2794 0.1778)
							(mid 0.249642 0.249642)
							(end 0.1778 0.2794)
						)
					)
					(width 0)
					(fill yes)
				)
			)
		)
		(pad "2" smd custom
			(at 0 0.4445 90)
			(size 0.1397 0.1397)
			(layers "B.Cu" "B.Mask" "B.Paste")
			(net "SMB_HOST_STBY_LVC3_SCL_R5")
			(options
				(clearance outline)
				(anchor circle)
			)
			(primitives
				(gr_poly
					(pts
						(arc
							(start -0.1778 0.2794)
							(mid -0.249642 0.249642)
							(end -0.2794 0.1778)
						)
						(arc
							(start -0.2794 -0.1778)
							(mid -0.249642 -0.249642)
							(end -0.1778 -0.2794)
						)
						(arc
							(start 0.1778 -0.2794)
							(mid 0.249642 -0.249642)
							(end 0.2794 -0.1778)
						)
						(arc
							(start 0.2794 0.1778)
							(mid 0.249642 0.249642)
							(end 0.1778 0.2794)
						)
					)
					(width 0)
					(fill yes)
				)
			)
		)
	)
)
